(kicad_pcb
	(version 20260206)
	(generator "pcbnew")
	(generator_version "10.0")
	(general
		(thickness 1.6)
		(legacy_teardrops no)
	)
	(paper "A4")
	(title_block
		(title "01162023_DA0F0TEBIF0_F0T_Expander_BD_F_brd_V02_OCP.brd")
		(comment 1 "Grand Teton / footprints 4194-4199 of 9728")
	)
	(layers
		(0 "F.Cu" signal "TOP")
		(4 "In1.Cu" signal "GND")
		(6 "In2.Cu" signal "VCC")
		(8 "In3.Cu" signal "VCC1")
		(10 "In4.Cu" signal "GND1")
		(12 "In5.Cu" signal "IN1")
		(14 "In6.Cu" signal "GND2")
		(16 "In7.Cu" signal "IN2")
		(18 "In8.Cu" signal "GND3")
		(20 "In9.Cu" signal "IN3")
		(22 "In10.Cu" signal "GND4")
		(24 "In11.Cu" signal "IN4")
		(26 "In12.Cu" signal "GND5")
		(28 "In13.Cu" signal "IN5")
		(30 "In14.Cu" signal "GND6")
		(32 "In15.Cu" signal "IN6")
		(34 "In16.Cu" signal "GND7")
		(2 "B.Cu" signal "BOTTOM")
		(9 "F.Adhes" user "F.Adhesive")
		(11 "B.Adhes" user "B.Adhesive")
		(13 "F.Paste" user "Package Geometry/Pastemask Top")
		(15 "B.Paste" user "Package Geometry/Pastemask Bottom")
		(5 "F.SilkS" user "Ref Des/Silkscreen Top")
		(7 "B.SilkS" user "Ref Des/Silkscreen Bottom")
		(1 "F.Mask" user "Board Geometry/Soldermask Top")
		(3 "B.Mask" user "Board Geometry/Soldermask Bottom")
		(17 "Dwgs.User" user "User.Drawings")
		(19 "Cmts.User" user "User.Comments")
		(21 "Eco1.User" user "User.Eco1")
		(23 "Eco2.User" user "User.Eco2")
		(25 "Edge.Cuts" user "Board Geometry/Outline")
		(27 "Margin" user)
		(31 "F.CrtYd" user "Package Geometry/Place Bound Top")
		(29 "B.CrtYd" user "Package Geometry/Place Bound Bottom")
		(35 "F.Fab" user "Ref Des/Assembly Top")
		(33 "B.Fab" user "Ref Des/Assembly Bottom")
	)
	(footprint ""
		(layer "F.Cu")
		(at 319.696084 -390.990836 180)
		(property "Reference" "R1849"
			(at 0 0 180)
			(layer "F.SilkS")
			(hide yes)
			(effects
				(font
					(size 1.27 1.27)
				)
			)
		)
		(property "Value" ""
			(at 0 0 180)
			(layer "F.Fab")
			(effects
				(font
					(size 1.27 1.27)
				)
			)
		)
		(duplicate_pad_numbers_are_jumpers no)
		(fp_line
			(start 0.7874 0.4064)
			(end -0.7874 0.4064)
			(stroke
				(width 0.1524)
				(type default)
			)
			(layer "F.SilkS")
		)
		(fp_line
			(start 0.7874 -0.4064)
			(end 0.7874 0.4064)
			(stroke
				(width 0.1524)
				(type default)
			)
			(layer "F.SilkS")
		)
		(fp_line
			(start -0.7874 0.4064)
			(end -0.7874 -0.4064)
			(stroke
				(width 0.1524)
				(type default)
			)
			(layer "F.SilkS")
		)
		(fp_line
			(start -0.7874 -0.4064)
			(end 0.7874 -0.4064)
			(stroke
				(width 0.1524)
				(type default)
			)
			(layer "F.SilkS")
		)
		(fp_line
			(start 0.67945 0.3048)
			(end 0.120396 0.3048)
			(stroke
				(width 0.1)
				(type default)
			)
			(layer "F.Fab")
		)
		(fp_line
			(start 0.67945 -0.3048)
			(end 0.67945 0.3048)
			(stroke
				(width 0.1)
				(type default)
			)
			(layer "F.Fab")
		)
		(fp_line
			(start 0.12065 -0.2794)
			(end 0.12065 -0.3048)
			(stroke
				(width 0.1)
				(type default)
			)
			(layer "F.Fab")
		)
		(fp_line
			(start 0.12065 -0.3048)
			(end 0.67945 -0.3048)
			(stroke
				(width 0.1)
				(type default)
			)
			(layer "F.Fab")
		)
		(fp_line
			(start 0.120396 0.3048)
			(end 0.120396 0.2794)
			(stroke
				(width 0.1)
				(type default)
			)
			(layer "F.Fab")
		)
		(fp_line
			(start 0.120396 0.2794)
			(end -0.12065 0.2794)
			(stroke
				(width 0.1)
				(type default)
			)
			(layer "F.Fab")
		)
		(fp_line
			(start -0.12065 0.3048)
			(end -0.67945 0.3048)
			(stroke
				(width 0.1)
				(type default)
			)
			(layer "F.Fab")
		)
		(fp_line
			(start -0.12065 0.2794)
			(end -0.12065 0.3048)
			(stroke
				(width 0.1)
				(type default)
			)
			(layer "F.Fab")
		)
		(fp_line
			(start -0.12065 -0.2794)
			(end 0.12065 -0.2794)
			(stroke
				(width 0.1)
				(type default)
			)
			(layer "F.Fab")
		)
		(fp_line
			(start -0.12065 -0.305054)
			(end -0.12065 -0.2794)
			(stroke
				(width 0.1)
				(type default)
			)
			(layer "F.Fab")
		)
		(fp_line
			(start -0.67945 0.3048)
			(end -0.67945 -0.305054)
			(stroke
				(width 0.1)
				(type default)
			)
			(layer "F.Fab")
		)
		(fp_line
			(start -0.67945 -0.305054)
			(end -0.12065 -0.305054)
			(stroke
				(width 0.1)
				(type default)
			)
			(layer "F.Fab")
		)
		(pad "1" smd circle
			(at -0.40005 0 180)
			(size 0 0)
			(layers "F.Cu" "F.Mask" "F.Paste")
			(net "GPU_3V3IO_RSVD3_FFU_R")
		)
		(pad "2" smd circle
			(at 0.40005 0 180)
			(size 0 0)
			(layers "F.Cu" "F.Mask" "F.Paste")
			(net "GPU_3V3IO_RSVD3_FFU")
		)
	)
	(footprint ""
		(layer "F.Cu")
		(at 200.990962 -55.663846 90)
		(property "Reference" "PU61"
			(at -1.597406 2.829052 90)
			(unlocked yes)
			(layer "F.SilkS")
			(effects
				(font
					(size 0.7874 0.5842)
					(thickness 0.1524)
				)
				(justify left)
			)
		)
		(property "Value" ""
			(at 0 0 90)
			(layer "F.Fab")
			(effects
				(font
					(size 1.27 1.27)
				)
			)
		)
		(duplicate_pad_numbers_are_jumpers no)
		(fp_line
			(start 1.943608 -1.549908)
			(end 1.943608 1.549908)
			(stroke
				(width 0.1524)
				(type default)
			)
			(layer "F.SilkS")
		)
		(fp_line
			(start -1.943608 -1.549908)
			(end 1.943608 -1.549908)
			(stroke
				(width 0.1524)
				(type default)
			)
			(layer "F.SilkS")
		)
		(fp_line
			(start 1.943608 1.549908)
			(end -1.943608 1.549908)
			(stroke
				(width 0.1524)
				(type default)
			)
			(layer "F.SilkS")
		)
		(fp_line
			(start -1.943608 1.549908)
			(end -1.943608 -1.549908)
			(stroke
				(width 0.1524)
				(type default)
			)
			(layer "F.SilkS")
		)
		(fp_poly
			(pts
				(xy -2.019808 -1.549908) (xy -1.257808 -1.549908) (xy -1.257808 -1.880108) (xy -2.019808 -1.880108)
			)
			(stroke
				(width 0)
				(type default)
			)
			(fill yes)
			(layer "F.SilkS")
		)
		(fp_line
			(start 1.549908 -1.549908)
			(end 1.549908 1.549908)
			(stroke
				(width 0.1)
				(type default)
			)
			(layer "F.Fab")
		)
		(fp_line
			(start -1.549908 -1.549908)
			(end 1.549908 -1.549908)
			(stroke
				(width 0.1)
				(type default)
			)
			(layer "F.Fab")
		)
		(fp_line
			(start 1.549908 1.549908)
			(end -1.549908 1.549908)
			(stroke
				(width 0.1)
				(type default)
			)
			(layer "F.Fab")
		)
		(fp_line
			(start -1.549908 1.549908)
			(end -1.549908 -1.549908)
			(stroke
				(width 0.1)
				(type default)
			)
			(layer "F.Fab")
		)
		(fp_poly
			(pts
				(xy -2.019808 -1.549908) (xy -1.257808 -1.549908) (xy -1.257808 -1.880108) (xy -2.019808 -1.880108)
			)
			(stroke
				(width 0)
				(type default)
			)
			(fill yes)
			(layer "F.Fab")
		)
		(pad "1" smd rect
			(at -1.500124 -1.249934)
			(size 0.2794 0.6096)
			(layers "F.Cu" "F.Mask" "F.Paste")
			(net "P3V3_SSD7")
		)
		(pad "2" smd rect
			(at -1.500124 -0.750062)
			(size 0.2794 0.6096)
			(layers "F.Cu" "F.Mask" "F.Paste")
			(net "P3V3_SSD7")
		)
		(pad "3" smd rect
			(at -1.500124 -0.249936)
			(size 0.2794 0.6096)
			(layers "F.Cu" "F.Mask" "F.Paste")
			(net "P3V3_SSD7")
		)
		(pad "4" smd rect
			(at -1.500124 0.249936)
			(size 0.2794 0.6096)
			(layers "F.Cu" "F.Mask" "F.Paste")
			(net "P3V3_SSD7")
		)
		(pad "5" smd rect
			(at -1.500124 0.750062)
			(size 0.2794 0.6096)
			(layers "F.Cu" "F.Mask" "F.Paste")
			(net "P3V3_SSD7")
		)
		(pad "6" smd rect
			(at -1.500124 1.249934)
			(size 0.2794 0.6096)
			(layers "F.Cu" "F.Mask" "F.Paste")
			(net "GND")
		)
		(pad "7" smd rect
			(at 1.500124 1.249934)
			(size 0.2794 0.6096)
			(layers "F.Cu" "F.Mask" "F.Paste")
			(net "P3V3_SSD7_SS")
		)
		(pad "8" smd rect
			(at 1.500124 0.750062)
			(size 0.2794 0.6096)
			(layers "F.Cu" "F.Mask" "F.Paste")
			(net "PWRGD_P3V3_SSD7")
		)
		(pad "9" smd rect
			(at 1.500124 0.249936)
			(size 0.2794 0.6096)
			(layers "F.Cu" "F.Mask" "F.Paste")
			(net "P3V3_SSD7_OCP")
		)
		(pad "10" smd rect
			(at 1.500124 -0.249936)
			(size 0.2794 0.6096)
			(layers "F.Cu" "F.Mask" "F.Paste")
			(net "P5V_AUX")
		)
		(pad "11" smd rect
			(at 1.500124 -0.750062)
			(size 0.2794 0.6096)
			(layers "F.Cu" "F.Mask" "F.Paste")
			(net "SSD7_AUX_P3V3_EN_R")
		)
		(pad "12" smd rect
			(at 1.500124 -1.249934)
			(size 0.2794 0.6096)
			(layers "F.Cu" "F.Mask" "F.Paste")
			(net "P3V3_AUX")
		)
		(pad "13" smd rect
			(at 0 0 90)
			(size 1.9812 2.7178)
			(layers "F.Cu" "F.Mask" "F.Paste")
			(net "P3V3_AUX")
		)
		(zone
			(layer "F.Cu")
			(hatch none 0.5)
			(connect_pads
				(clearance 0)
			)
			(min_thickness 0.25)
			(keepout
				(tracks not_allowed)
				(vias allowed)
				(pads allowed)
				(copperpour not_allowed)
				(footprints allowed)
			)
			(placement
				(enabled no)
				(sheetname "")
			)
			(fill
				(thermal_gap 0.5)
				(thermal_bridge_width 0.5)
				(island_removal_mode 0)
			)
			(polygon
				(pts
					(xy 199.441562 -56.806846) (xy 199.568562 -56.806846) (xy 202.540362 -56.806846) (xy 202.54087 -56.806846)
					(xy 202.54087 -54.520846) (xy 202.540362 -54.520846) (xy 202.413362 -54.520846) (xy 200.990962 -54.520846)
					(xy 200.990962 -54.622446) (xy 202.413362 -54.622446) (xy 202.413362 -56.705246) (xy 199.568562 -56.705246)
					(xy 199.568562 -54.622446) (xy 200.965562 -54.622446) (xy 200.965562 -54.520846) (xy 199.568562 -54.520846)
					(xy 199.441562 -54.520846) (xy 199.441054 -54.520846) (xy 199.441054 -56.806846)
				)
			)
		)
	)
	(footprint ""
		(layer "F.Cu")
		(at 36.638484 -105.609898)
		(property "Reference" "C58"
			(at 0 0 0)
			(layer "F.SilkS")
			(hide yes)
			(effects
				(font
					(size 1.27 1.27)
				)
			)
		)
		(property "Value" ""
			(at 0 0 0)
			(layer "F.Fab")
			(effects
				(font
					(size 1.27 1.27)
				)
			)
		)
		(duplicate_pad_numbers_are_jumpers no)
		(fp_line
			(start -0.299974 -0.150114)
			(end 0.299974 -0.150114)
			(stroke
				(width 0.1)
				(type default)
			)
			(layer "F.Fab")
		)
		(fp_line
			(start -0.299974 0.150114)
			(end -0.299974 -0.150114)
			(stroke
				(width 0.1)
				(type default)
			)
			(layer "F.Fab")
		)
		(fp_line
			(start 0.299974 -0.150114)
			(end 0.299974 0.150114)
			(stroke
				(width 0.1)
				(type default)
			)
			(layer "F.Fab")
		)
		(fp_line
			(start 0.299974 0.150114)
			(end -0.299974 0.150114)
			(stroke
				(width 0.1)
				(type default)
			)
			(layer "F.Fab")
		)
		(pad "1" smd rect
			(at -0.2667 0)
			(size 0.3048 0.381)
			(layers "F.Cu" "F.Mask" "F.Paste")
			(net "P5E_PEX0_STN1_TX_DP<19>")
		)
		(pad "2" smd rect
			(at 0.2667 0)
			(size 0.3048 0.381)
			(layers "F.Cu" "F.Mask" "F.Paste")
			(net "P5E_PEX0_STN1_TX_C_DP<19>")
		)
	)
	(footprint ""
		(layer "F.Cu")
		(at 257.171698 -350.722438)
		(property "Reference" "R6653"
			(at 0 0 0)
			(layer "F.SilkS")
			(hide yes)
			(effects
				(font
					(size 1.27 1.27)
				)
			)
		)
		(property "Value" ""
			(at 0 0 0)
			(layer "F.Fab")
			(effects
				(font
					(size 1.27 1.27)
				)
			)
		)
		(duplicate_pad_numbers_are_jumpers no)
		(fp_line
			(start -0.7874 -0.4064)
			(end 0.7874 -0.4064)
			(stroke
				(width 0.1524)
				(type default)
			)
			(layer "F.SilkS")
		)
		(fp_line
			(start -0.7874 0.4064)
			(end -0.7874 -0.4064)
			(stroke
				(width 0.1524)
				(type default)
			)
			(layer "F.SilkS")
		)
		(fp_line
			(start 0.7874 -0.4064)
			(end 0.7874 0.4064)
			(stroke
				(width 0.1524)
				(type default)
			)
			(layer "F.SilkS")
		)
		(fp_line
			(start 0.7874 0.4064)
			(end -0.7874 0.4064)
			(stroke
				(width 0.1524)
				(type default)
			)
			(layer "F.SilkS")
		)
		(fp_line
			(start -0.67945 -0.305054)
			(end -0.12065 -0.305054)
			(stroke
				(width 0.1)
				(type default)
			)
			(layer "F.Fab")
		)
		(fp_line
			(start -0.67945 0.3048)
			(end -0.67945 -0.305054)
			(stroke
				(width 0.1)
				(type default)
			)
			(layer "F.Fab")
		)
		(fp_line
			(start -0.12065 -0.305054)
			(end -0.12065 -0.2794)
			(stroke
				(width 0.1)
				(type default)
			)
			(layer "F.Fab")
		)
		(fp_line
			(start -0.12065 -0.2794)
			(end 0.12065 -0.2794)
			(stroke
				(width 0.1)
				(type default)
			)
			(layer "F.Fab")
		)
		(fp_line
			(start -0.12065 0.2794)
			(end -0.12065 0.3048)
			(stroke
				(width 0.1)
				(type default)
			)
			(layer "F.Fab")
		)
		(fp_line
			(start -0.12065 0.3048)
			(end -0.67945 0.3048)
			(stroke
				(width 0.1)
				(type default)
			)
			(layer "F.Fab")
		)
		(fp_line
			(start 0.120396 0.2794)
			(end -0.12065 0.2794)
			(stroke
				(width 0.1)
				(type default)
			)
			(layer "F.Fab")
		)
		(fp_line
			(start 0.120396 0.3048)
			(end 0.120396 0.2794)
			(stroke
				(width 0.1)
				(type default)
			)
			(layer "F.Fab")
		)
		(fp_line
			(start 0.12065 -0.3048)
			(end 0.67945 -0.3048)
			(stroke
				(width 0.1)
				(type default)
			)
			(layer "F.Fab")
		)
		(fp_line
			(start 0.12065 -0.2794)
			(end 0.12065 -0.3048)
			(stroke
				(width 0.1)
				(type default)
			)
			(layer "F.Fab")
		)
		(fp_line
			(start 0.67945 -0.3048)
			(end 0.67945 0.3048)
			(stroke
				(width 0.1)
				(type default)
			)
			(layer "F.Fab")
		)
		(fp_line
			(start 0.67945 0.3048)
			(end 0.120396 0.3048)
			(stroke
				(width 0.1)
				(type default)
			)
			(layer "F.Fab")
		)
		(pad "1" smd circle
			(at -0.40005 0)
			(size 0 0)
			(layers "F.Cu" "F.Mask" "F.Paste")
			(net "P3V3_AUX")
		)
		(pad "2" smd circle
			(at 0.40005 0)
			(size 0 0)
			(layers "F.Cu" "F.Mask" "F.Paste")
			(net "A_HSC_LOW_GATE")
		)
	)
	(footprint ""
		(layer "F.Cu")
		(at 451.467982 -114.833654 90)
		(property "Reference" "PR7054"
			(at 0 0 90)
			(layer "F.SilkS")
			(hide yes)
			(effects
				(font
					(size 1.27 1.27)
				)
			)
		)
		(property "Value" ""
			(at 0 0 90)
			(layer "F.Fab")
			(effects
				(font
					(size 1.27 1.27)
				)
			)
		)
		(duplicate_pad_numbers_are_jumpers no)
		(fp_line
			(start 1.2954 -0.5842)
			(end 1.2954 0.5842)
			(stroke
				(width 0.1524)
				(type default)
			)
			(layer "F.SilkS")
		)
		(fp_line
			(start -1.2954 -0.5842)
			(end 1.2954 -0.5842)
			(stroke
				(width 0.1524)
				(type default)
			)
			(layer "F.SilkS")
		)
		(fp_line
			(start 1.2954 0.5842)
			(end -1.2954 0.5842)
			(stroke
				(width 0.1524)
				(type default)
			)
			(layer "F.SilkS")
		)
		(fp_line
			(start -1.2954 0.5842)
			(end -1.2954 -0.5842)
			(stroke
				(width 0.1524)
				(type default)
			)
			(layer "F.SilkS")
		)
		(fp_line
			(start 0.8636 -0.4572)
			(end 0.8636 -0.406654)
			(stroke
				(width 0.1)
				(type default)
			)
			(layer "F.Fab")
		)
		(fp_line
			(start -0.8636 -0.4572)
			(end 0.8636 -0.4572)
			(stroke
				(width 0.1)
				(type default)
			)
			(layer "F.Fab")
		)
		(fp_line
			(start 1.1938 -0.406654)
			(end 1.1938 0.4064)
			(stroke
				(width 0.1)
				(type default)
			)
			(layer "F.Fab")
		)
		(fp_line
			(start 0.8636 -0.406654)
			(end 1.1938 -0.406654)
			(stroke
				(width 0.1)
				(type default)
			)
			(layer "F.Fab")
		)
		(fp_line
			(start -0.8636 -0.406654)
			(end -0.8636 -0.4572)
			(stroke
				(width 0.1)
				(type default)
			)
			(layer "F.Fab")
		)
		(fp_line
			(start -1.1938 -0.406654)
			(end -0.8636 -0.406654)
			(stroke
				(width 0.1)
				(type default)
			)
			(layer "F.Fab")
		)
		(fp_line
			(start 1.1938 0.4064)
			(end 0.8636 0.4064)
			(stroke
				(width 0.1)
				(type default)
			)
			(layer "F.Fab")
		)
		(fp_line
			(start 0.8636 0.4064)
			(end 0.8636 0.4572)
			(stroke
				(width 0.1)
				(type default)
			)
			(layer "F.Fab")
		)
		(fp_line
			(start -0.8636 0.4064)
			(end -1.1938 0.4064)
			(stroke
				(width 0.1)
				(type default)
			)
			(layer "F.Fab")
		)
		(fp_line
			(start -1.1938 0.4064)
			(end -1.1938 -0.406654)
			(stroke
				(width 0.1)
				(type default)
			)
			(layer "F.Fab")
		)
		(fp_line
			(start -0.8636 0.4318)
			(end -0.8636 0.4064)
			(stroke
				(width 0.1)
				(type default)
			)
			(layer "F.Fab")
		)
		(fp_line
			(start 0.8636 0.4572)
			(end -0.8636 0.4572)
			(stroke
				(width 0.1)
				(type default)
			)
			(layer "F.Fab")
		)
		(fp_line
			(start -0.8636 0.4572)
			(end -0.8636 0.4318)
			(stroke
				(width 0.1)
				(type default)
			)
			(layer "F.Fab")
		)
		(pad "1" smd rect
			(at -0.7366 0)
			(size 0.7112 0.8128)
			(layers "F.Cu" "F.Mask" "F.Paste")
			(net "P12V_NIC7_CO_AVIN_PD")
		)
		(pad "2" smd rect
			(at 0.7366 0)
			(size 0.7112 0.8128)
			(layers "F.Cu" "F.Mask" "F.Paste")
			(net "P12V_AUX")
		)
	)
	(footprint ""
		(layer "F.Cu")
		(at 336.931 -236.855 90)
		(property "Reference" "R1793"
			(at 0 0 90)
			(layer "F.SilkS")
			(hide yes)
			(effects
				(font
					(size 1.27 1.27)
				)
			)
		)
		(property "Value" ""
			(at 0 0 90)
			(layer "F.Fab")
			(effects
				(font
					(size 1.27 1.27)
				)
			)
		)
		(duplicate_pad_numbers_are_jumpers no)
		(fp_line
			(start 0.7874 -0.4064)
			(end 0.7874 0.4064)
			(stroke
				(width 0.1524)
				(type default)
			)
			(layer "F.SilkS")
		)
		(fp_line
			(start -0.7874 -0.4064)
			(end 0.7874 -0.4064)
			(stroke
				(width 0.1524)
				(type default)
			)
			(layer "F.SilkS")
		)
		(fp_line
			(start 0.7874 0.4064)
			(end -0.7874 0.4064)
			(stroke
				(width 0.1524)
				(type default)
			)
			(layer "F.SilkS")
		)
		(fp_line
			(start -0.7874 0.4064)
			(end -0.7874 -0.4064)
			(stroke
				(width 0.1524)
				(type default)
			)
			(layer "F.SilkS")
		)
		(fp_line
			(start -0.12065 -0.305054)
			(end -0.12065 -0.2794)
			(stroke
				(width 0.1)
				(type default)
			)
			(layer "F.Fab")
		)
		(fp_line
			(start -0.67945 -0.305054)
			(end -0.12065 -0.305054)
			(stroke
				(width 0.1)
				(type default)
			)
			(layer "F.Fab")
		)
		(fp_line
			(start 0.67945 -0.3048)
			(end 0.67945 0.3048)
			(stroke
				(width 0.1)
				(type default)
			)
			(layer "F.Fab")
		)
		(fp_line
			(start 0.12065 -0.3048)
			(end 0.67945 -0.3048)
			(stroke
				(width 0.1)
				(type default)
			)
			(layer "F.Fab")
		)
		(fp_line
			(start 0.12065 -0.2794)
			(end 0.12065 -0.3048)
			(stroke
				(width 0.1)
				(type default)
			)
			(layer "F.Fab")
		)
		(fp_line
			(start -0.12065 -0.2794)
			(end 0.12065 -0.2794)
			(stroke
				(width 0.1)
				(type default)
			)
			(layer "F.Fab")
		)
		(fp_line
			(start 0.120396 0.2794)
			(end -0.12065 0.2794)
			(stroke
				(width 0.1)
				(type default)
			)
			(layer "F.Fab")
		)
		(fp_line
			(start -0.12065 0.2794)
			(end -0.12065 0.3048)
			(stroke
				(width 0.1)
				(type default)
			)
			(layer "F.Fab")
		)
		(fp_line
			(start 0.67945 0.3048)
			(end 0.120396 0.3048)
			(stroke
				(width 0.1)
				(type default)
			)
			(layer "F.Fab")
		)
		(fp_line
			(start 0.120396 0.3048)
			(end 0.120396 0.2794)
			(stroke
				(width 0.1)
				(type default)
			)
			(layer "F.Fab")
		)
		(fp_line
			(start -0.12065 0.3048)
			(end -0.67945 0.3048)
			(stroke
				(width 0.1)
				(type default)
			)
			(layer "F.Fab")
		)
		(fp_line
			(start -0.67945 0.3048)
			(end -0.67945 -0.305054)
			(stroke
				(width 0.1)
				(type default)
			)
			(layer "F.Fab")
		)
		(pad "1" smd circle
			(at -0.40005 0 90)
			(size 0 0)
			(layers "F.Cu" "F.Mask" "F.Paste")
			(net "P3V3_AUX")
		)
		(pad "2" smd circle
			(at 0.40005 0 90)
			(size 0 0)
			(layers "F.Cu" "F.Mask" "F.Paste")
			(net "MB_SWB_PWR_EN_ISO_R")
		)
	)
)
